# S9S_MB_2U (Grand Teton) — schematic netlist excerpt (pin names and nets, part order shuffled) for the footprints in the layout excerpt that follows; sources: Cadence DE-HDL packaged netlist, KiCad conversion of 03242023_DA0F0TMBIJ0_F0T_Motherboard_J_brd_V01_OCP.brd

R740  Q_RES  10K 1% CHIP  pkg 0402LF  page 133 : A = P3V3_AUX ; B = FM_CPU0_SKTOCC_N
R3858  Q_RES  33.2 1% CHIP  pkg 0402LF  page 240 : A = SMB_OCP_V3_2_3V3AUX_SDA ; B = SMB_OCP_V3_2_3V3AUX_SDA_R0

(kicad_pcb
	(version 20260206)
	(generator "pcbnew")
	(generator_version "10.0")
	(general
		(thickness 1.6)
		(legacy_teardrops no)
	)
	(paper "A4")
	(title_block
		(title "03242023_DA0F0TMBIJ0_F0T_Motherboard_J_brd_V01_OCP.brd")
		(comment 1 "Grand Teton / footprints 5502-5503 of 6105")
	)
	(layers
		(0 "F.Cu" signal "TOP")
		(4 "In1.Cu" signal "GND")
		(6 "In2.Cu" signal "IN1")
		(8 "In3.Cu" signal "GND1")
		(10 "In4.Cu" signal "IN2")
		(12 "In5.Cu" signal "GND2")
		(14 "In6.Cu" signal "IN3")
		(16 "In7.Cu" signal "GND3")
		(18 "In8.Cu" signal "VCC")
		(20 "In9.Cu" signal "VCC1")
		(22 "In10.Cu" signal "GND4")
		(24 "In11.Cu" signal "IN4")
		(26 "In12.Cu" signal "GND5")
		(28 "In13.Cu" signal "IN5")
		(30 "In14.Cu" signal "GND6")
		(32 "In15.Cu" signal "IN6")
		(34 "In16.Cu" signal "GND7")
		(2 "B.Cu" signal "BOTTOM")
		(9 "F.Adhes" user "F.Adhesive")
		(11 "B.Adhes" user "B.Adhesive")
		(13 "F.Paste" user "Package Geometry/Pastemask Top")
		(15 "B.Paste" user "Package Geometry/Pastemask Bottom")
		(5 "F.SilkS" user "Ref Des/Silkscreen Top")
		(7 "B.SilkS" user "Ref Des/Silkscreen Bottom")
		(1 "F.Mask" user "Board Geometry/Soldermask Top")
		(3 "B.Mask" user "Board Geometry/Soldermask Bottom")
		(17 "Dwgs.User" user "User.Drawings")
		(19 "Cmts.User" user "User.Comments")
		(21 "Eco1.User" user "User.Eco1")
		(23 "Eco2.User" user "User.Eco2")
		(25 "Edge.Cuts" user "Board Geometry/Outline")
		(27 "Margin" user)
		(31 "F.CrtYd" user "Package Geometry/Place Bound Top")
		(29 "B.CrtYd" user "Package Geometry/Place Bound Bottom")
		(35 "F.Fab" user "Ref Des/Assembly Top")
		(33 "B.Fab" user "Ref Des/Assembly Bottom")
	)
	(footprint ""
		(layer "B.Cu")
		(at 200.031858 -192.95237)
		(property "Reference" "R740"
			(at 0 0 0)
			(layer "B.SilkS")
			(hide yes)
			(effects
				(font
					(size 1.27 1.27)
				)
				(justify mirror)
			)
		)
		(property "Value" ""
			(at 0 0 0)
			(layer "B.Fab")
			(effects
				(font
					(size 1.27 1.27)
				)
				(justify mirror)
			)
		)
		(duplicate_pad_numbers_are_jumpers no)
		(fp_line
			(start -0.7874 -0.4064)
			(end -0.7874 0.4064)
			(stroke
				(width 0.1524)
				(type default)
			)
			(layer "B.SilkS")
		)
		(fp_line
			(start -0.7874 0.4064)
			(end 0.7874 0.4064)
			(stroke
				(width 0.1524)
				(type default)
			)
			(layer "B.SilkS")
		)
		(fp_line
			(start 0.7874 -0.4064)
			(end -0.7874 -0.4064)
			(stroke
				(width 0.1524)
				(type default)
			)
			(layer "B.SilkS")
		)
		(fp_line
			(start 0.7874 0.4064)
			(end 0.7874 -0.4064)
			(stroke
				(width 0.1524)
				(type default)
			)
			(layer "B.SilkS")
		)
		(fp_line
			(start -0.67945 -0.3048)
			(end -0.67945 0.3048)
			(stroke
				(width 0.1)
				(type default)
			)
			(layer "B.Fab")
		)
		(fp_line
			(start -0.67945 0.3048)
			(end -0.120396 0.3048)
			(stroke
				(width 0.1)
				(type default)
			)
			(layer "B.Fab")
		)
		(fp_line
			(start -0.12065 -0.3048)
			(end -0.67945 -0.3048)
			(stroke
				(width 0.1)
				(type default)
			)
			(layer "B.Fab")
		)
		(fp_line
			(start -0.12065 -0.2794)
			(end -0.12065 -0.3048)
			(stroke
				(width 0.1)
				(type default)
			)
			(layer "B.Fab")
		)
		(fp_line
			(start -0.120396 0.2794)
			(end 0.12065 0.2794)
			(stroke
				(width 0.1)
				(type default)
			)
			(layer "B.Fab")
		)
		(fp_line
			(start -0.120396 0.3048)
			(end -0.120396 0.2794)
			(stroke
				(width 0.1)
				(type default)
			)
			(layer "B.Fab")
		)
		(fp_line
			(start 0.12065 -0.305054)
			(end 0.12065 -0.2794)
			(stroke
				(width 0.1)
				(type default)
			)
			(layer "B.Fab")
		)
		(fp_line
			(start 0.12065 -0.2794)
			(end -0.12065 -0.2794)
			(stroke
				(width 0.1)
				(type default)
			)
			(layer "B.Fab")
		)
		(fp_line
			(start 0.12065 0.2794)
			(end 0.12065 0.3048)
			(stroke
				(width 0.1)
				(type default)
			)
			(layer "B.Fab")
		)
		(fp_line
			(start 0.12065 0.3048)
			(end 0.67945 0.3048)
			(stroke
				(width 0.1)
				(type default)
			)
			(layer "B.Fab")
		)
		(fp_line
			(start 0.67945 -0.305054)
			(end 0.12065 -0.305054)
			(stroke
				(width 0.1)
				(type default)
			)
			(layer "B.Fab")
		)
		(fp_line
			(start 0.67945 0.3048)
			(end 0.67945 -0.305054)
			(stroke
				(width 0.1)
				(type default)
			)
			(layer "B.Fab")
		)
		(pad "1" smd circle
			(at 0.40005 0 180)
			(size 0 0)
			(layers "B.Cu" "B.Mask" "B.Paste")
			(net "P3V3_AUX")
		)
		(pad "2" smd circle
			(at -0.40005 0 180)
			(size 0 0)
			(layers "B.Cu" "B.Mask" "B.Paste")
			(net "FM_CPU0_SKTOCC_N")
		)
	)
	(footprint ""
		(layer "B.Cu")
		(at 172.2247 -13.762228 90)
		(property "Reference" "R3858"
			(at 0 0 90)
			(layer "B.SilkS")
			(hide yes)
			(effects
				(font
					(size 1.27 1.27)
				)
				(justify mirror)
			)
		)
		(property "Value" ""
			(at 0 0 90)
			(layer "B.Fab")
			(effects
				(font
					(size 1.27 1.27)
				)
				(justify mirror)
			)
		)
		(duplicate_pad_numbers_are_jumpers no)
		(fp_line
			(start 0.7874 -0.4064)
			(end -0.7874 -0.4064)
			(stroke
				(width 0.1524)
				(type default)
			)
			(layer "B.SilkS")
		)
		(fp_line
			(start -0.7874 -0.4064)
			(end -0.7874 0.4064)
			(stroke
				(width 0.1524)
				(type default)
			)
			(layer "B.SilkS")
		)
		(fp_line
			(start 0.7874 0.4064)
			(end 0.7874 -0.4064)
			(stroke
				(width 0.1524)
				(type default)
			)
			(layer "B.SilkS")
		)
		(fp_line
			(start -0.7874 0.4064)
			(end 0.7874 0.4064)
			(stroke
				(width 0.1524)
				(type default)
			)
			(layer "B.SilkS")
		)
		(fp_line
			(start 0.67945 -0.305054)
			(end 0.12065 -0.305054)
			(stroke
				(width 0.1)
				(type default)
			)
			(layer "B.Fab")
		)
		(fp_line
			(start 0.12065 -0.305054)
			(end 0.12065 -0.2794)
			(stroke
				(width 0.1)
				(type default)
			)
			(layer "B.Fab")
		)
		(fp_line
			(start -0.12065 -0.3048)
			(end -0.67945 -0.3048)
			(stroke
				(width 0.1)
				(type default)
			)
			(layer "B.Fab")
		)
		(fp_line
			(start -0.67945 -0.3048)
			(end -0.67945 0.3048)
			(stroke
				(width 0.1)
				(type default)
			)
			(layer "B.Fab")
		)
		(fp_line
			(start 0.12065 -0.2794)
			(end -0.12065 -0.2794)
			(stroke
				(width 0.1)
				(type default)
			)
			(layer "B.Fab")
		)
		(fp_line
			(start -0.12065 -0.2794)
			(end -0.12065 -0.3048)
			(stroke
				(width 0.1)
				(type default)
			)
			(layer "B.Fab")
		)
		(fp_line
			(start 0.12065 0.2794)
			(end 0.12065 0.3048)
			(stroke
				(width 0.1)
				(type default)
			)
			(layer "B.Fab")
		)
		(fp_line
			(start -0.120396 0.2794)
			(end 0.12065 0.2794)
			(stroke
				(width 0.1)
				(type default)
			)
			(layer "B.Fab")
		)
		(fp_line
			(start 0.67945 0.3048)
			(end 0.67945 -0.305054)
			(stroke
				(width 0.1)
				(type default)
			)
			(layer "B.Fab")
		)
		(fp_line
			(start 0.12065 0.3048)
			(end 0.67945 0.3048)
			(stroke
				(width 0.1)
				(type default)
			)
			(layer "B.Fab")
		)
		(fp_line
			(start -0.120396 0.3048)
			(end -0.120396 0.2794)
			(stroke
				(width 0.1)
				(type default)
			)
			(layer "B.Fab")
		)
		(fp_line
			(start -0.67945 0.3048)
			(end -0.120396 0.3048)
			(stroke
				(width 0.1)
				(type default)
			)
			(layer "B.Fab")
		)
		(pad "1" smd circle
			(at 0.40005 0 270)
			(size 0 0)
			(layers "B.Cu" "B.Mask" "B.Paste")
			(net "SMB_OCP_V3_2_3V3AUX_SDA")
		)
		(pad "2" smd circle
			(at -0.40005 0 270)
			(size 0 0)
			(layers "B.Cu" "B.Mask" "B.Paste")
			(net "SMB_OCP_V3_2_3V3AUX_SDA_R0")
		)
	)
)
